(kicad_pcb
	(version 20260206)
	(generator "pcbnew")
	(generator_version "10.0")
	(general
		(thickness 1.6)
		(legacy_teardrops no)
	)
	(paper "A4")
	(title_block
		(title "03242023_DA0F0TMBIJ0_F0T_Motherboard_J_brd_V01_OCP.brd")
		(comment 1 "Grand Teton / footprints 1425-1432 of 6105")
	)
	(layers
		(0 "F.Cu" signal "TOP")
		(4 "In1.Cu" signal "GND")
		(6 "In2.Cu" signal "IN1")
		(8 "In3.Cu" signal "GND1")
		(10 "In4.Cu" signal "IN2")
		(12 "In5.Cu" signal "GND2")
		(14 "In6.Cu" signal "IN3")
		(16 "In7.Cu" signal "GND3")
		(18 "In8.Cu" signal "VCC")
		(20 "In9.Cu" signal "VCC1")
		(22 "In10.Cu" signal "GND4")
		(24 "In11.Cu" signal "IN4")
		(26 "In12.Cu" signal "GND5")
		(28 "In13.Cu" signal "IN5")
		(30 "In14.Cu" signal "GND6")
		(32 "In15.Cu" signal "IN6")
		(34 "In16.Cu" signal "GND7")
		(2 "B.Cu" signal "BOTTOM")
		(9 "F.Adhes" user "F.Adhesive")
		(11 "B.Adhes" user "B.Adhesive")
		(13 "F.Paste" user "Package Geometry/Pastemask Top")
		(15 "B.Paste" user "Package Geometry/Pastemask Bottom")
		(5 "F.SilkS" user "Ref Des/Silkscreen Top")
		(7 "B.SilkS" user "Ref Des/Silkscreen Bottom")
		(1 "F.Mask" user "Board Geometry/Soldermask Top")
		(3 "B.Mask" user "Board Geometry/Soldermask Bottom")
		(17 "Dwgs.User" user "User.Drawings")
		(19 "Cmts.User" user "User.Comments")
		(21 "Eco1.User" user "User.Eco1")
		(23 "Eco2.User" user "User.Eco2")
		(25 "Edge.Cuts" user "Board Geometry/Outline")
		(27 "Margin" user)
		(31 "F.CrtYd" user "Package Geometry/Place Bound Top")
		(29 "B.CrtYd" user "Package Geometry/Place Bound Bottom")
		(35 "F.Fab" user "Ref Des/Assembly Top")
		(33 "B.Fab" user "Ref Des/Assembly Bottom")
	)
	(footprint ""
		(layer "F.Cu")
		(at 22.364192 -399.532094 90)
		(property "Reference" "R3274"
			(at 0 0 90)
			(layer "F.SilkS")
			(hide yes)
			(effects
				(font
					(size 1.27 1.27)
				)
			)
		)
		(property "Value" ""
			(at 0 0 90)
			(layer "F.Fab")
			(effects
				(font
					(size 1.27 1.27)
				)
			)
		)
		(duplicate_pad_numbers_are_jumpers no)
		(fp_line
			(start 0.7874 -0.4064)
			(end 0.7874 0.4064)
			(stroke
				(width 0.1524)
				(type default)
			)
			(layer "F.SilkS")
		)
		(fp_line
			(start -0.7874 -0.4064)
			(end 0.7874 -0.4064)
			(stroke
				(width 0.1524)
				(type default)
			)
			(layer "F.SilkS")
		)
		(fp_line
			(start 0.7874 0.4064)
			(end -0.7874 0.4064)
			(stroke
				(width 0.1524)
				(type default)
			)
			(layer "F.SilkS")
		)
		(fp_line
			(start -0.7874 0.4064)
			(end -0.7874 -0.4064)
			(stroke
				(width 0.1524)
				(type default)
			)
			(layer "F.SilkS")
		)
		(fp_line
			(start -0.12065 -0.305054)
			(end -0.12065 -0.2794)
			(stroke
				(width 0.1)
				(type default)
			)
			(layer "F.Fab")
		)
		(fp_line
			(start -0.67945 -0.305054)
			(end -0.12065 -0.305054)
			(stroke
				(width 0.1)
				(type default)
			)
			(layer "F.Fab")
		)
		(fp_line
			(start 0.67945 -0.3048)
			(end 0.67945 0.3048)
			(stroke
				(width 0.1)
				(type default)
			)
			(layer "F.Fab")
		)
		(fp_line
			(start 0.12065 -0.3048)
			(end 0.67945 -0.3048)
			(stroke
				(width 0.1)
				(type default)
			)
			(layer "F.Fab")
		)
		(fp_line
			(start 0.12065 -0.2794)
			(end 0.12065 -0.3048)
			(stroke
				(width 0.1)
				(type default)
			)
			(layer "F.Fab")
		)
		(fp_line
			(start -0.12065 -0.2794)
			(end 0.12065 -0.2794)
			(stroke
				(width 0.1)
				(type default)
			)
			(layer "F.Fab")
		)
		(fp_line
			(start 0.120396 0.2794)
			(end -0.12065 0.2794)
			(stroke
				(width 0.1)
				(type default)
			)
			(layer "F.Fab")
		)
		(fp_line
			(start -0.12065 0.2794)
			(end -0.12065 0.3048)
			(stroke
				(width 0.1)
				(type default)
			)
			(layer "F.Fab")
		)
		(fp_line
			(start 0.67945 0.3048)
			(end 0.120396 0.3048)
			(stroke
				(width 0.1)
				(type default)
			)
			(layer "F.Fab")
		)
		(fp_line
			(start 0.120396 0.3048)
			(end 0.120396 0.2794)
			(stroke
				(width 0.1)
				(type default)
			)
			(layer "F.Fab")
		)
		(fp_line
			(start -0.12065 0.3048)
			(end -0.67945 0.3048)
			(stroke
				(width 0.1)
				(type default)
			)
			(layer "F.Fab")
		)
		(fp_line
			(start -0.67945 0.3048)
			(end -0.67945 -0.305054)
			(stroke
				(width 0.1)
				(type default)
			)
			(layer "F.Fab")
		)
		(pad "1" smd circle
			(at -0.40005 0 90)
			(size 0 0)
			(layers "F.Cu" "F.Mask" "F.Paste")
			(net "FM_P2E_EQA0")
		)
		(pad "2" smd circle
			(at 0.40005 0 90)
			(size 0 0)
			(layers "F.Cu" "F.Mask" "F.Paste")
			(net "GND")
		)
	)
	(footprint ""
		(layer "F.Cu")
		(at 46.697138 -337.477608)
		(property "Reference" "PC415"
			(at 0 0 0)
			(layer "F.SilkS")
			(hide yes)
			(effects
				(font
					(size 1.27 1.27)
				)
			)
		)
		(property "Value" ""
			(at 0 0 0)
			(layer "F.Fab")
			(effects
				(font
					(size 1.27 1.27)
				)
			)
		)
		(duplicate_pad_numbers_are_jumpers no)
		(fp_line
			(start 2.750058 0.999998)
			(end -2.750058 0.999998)
			(stroke
				(width 0.1524)
				(type default)
			)
			(layer "F.SilkS")
		)
		(fp_circle
			(center 0 0.999998)
			(end 2.750058 0.999998)
			(stroke
				(width 0.1524)
				(type default)
			)
			(fill no)
			(layer "F.SilkS")
		)
		(fp_poly
			(pts
				(arc
					(start 2.750058 0.999998)
					(mid 0 3.750056)
					(end -2.750058 0.999998)
				)
			)
			(stroke
				(width 0)
				(type default)
			)
			(fill yes)
			(layer "F.SilkS")
		)
		(fp_circle
			(center 0 0.999998)
			(end 2.750058 0.999998)
			(stroke
				(width 0.1)
				(type default)
			)
			(fill no)
			(layer "F.Fab")
		)
		(pad "1" thru_hole rect
			(at 0 0)
			(size 1.5748 1.5748)
			(drill 1.0668)
			(layers "*.Cu" "*.Mask")
			(remove_unused_layers no)
			(net "PVCCFA_EHV_FIVRA_CPU1")
			(clearance 0)
			(padstack
				(mode front_inner_back)
				(layer "Inner"
					(shape circle)
					(size 1.5748 1.5748)
					(clearance 0)
				)
				(layer "B.Cu"
					(shape rect)
					(size 1.5748 1.5748)
					(clearance 0)
				)
			)
		)
		(pad "2" thru_hole circle
			(at 0 1.999996)
			(size 1.5748 1.5748)
			(drill 1.0668)
			(layers "*.Cu" "*.Mask")
			(remove_unused_layers no)
			(net "GND")
			(clearance 0)
		)
	)
	(footprint ""
		(layer "F.Cu")
		(at 171.50588 -133.695948 -90)
		(property "Reference" "R3048"
			(at 0 0 270)
			(layer "F.SilkS")
			(hide yes)
			(effects
				(font
					(size 1.27 1.27)
				)
			)
		)
		(property "Value" ""
			(at 0 0 270)
			(layer "F.Fab")
			(effects
				(font
					(size 1.27 1.27)
				)
			)
		)
		(duplicate_pad_numbers_are_jumpers no)
		(fp_line
			(start -0.7874 0.4064)
			(end -0.7874 -0.4064)
			(stroke
				(width 0.1524)
				(type default)
			)
			(layer "F.SilkS")
		)
		(fp_line
			(start 0.7874 0.4064)
			(end -0.7874 0.4064)
			(stroke
				(width 0.1524)
				(type default)
			)
			(layer "F.SilkS")
		)
		(fp_line
			(start -0.7874 -0.4064)
			(end 0.7874 -0.4064)
			(stroke
				(width 0.1524)
				(type default)
			)
			(layer "F.SilkS")
		)
		(fp_line
			(start 0.7874 -0.4064)
			(end 0.7874 0.4064)
			(stroke
				(width 0.1524)
				(type default)
			)
			(layer "F.SilkS")
		)
		(fp_line
			(start -0.67945 0.3048)
			(end -0.67945 -0.305054)
			(stroke
				(width 0.1)
				(type default)
			)
			(layer "F.Fab")
		)
		(fp_line
			(start -0.12065 0.3048)
			(end -0.67945 0.3048)
			(stroke
				(width 0.1)
				(type default)
			)
			(layer "F.Fab")
		)
		(fp_line
			(start 0.120396 0.3048)
			(end 0.120396 0.2794)
			(stroke
				(width 0.1)
				(type default)
			)
			(layer "F.Fab")
		)
		(fp_line
			(start 0.67945 0.3048)
			(end 0.120396 0.3048)
			(stroke
				(width 0.1)
				(type default)
			)
			(layer "F.Fab")
		)
		(fp_line
			(start -0.12065 0.2794)
			(end -0.12065 0.3048)
			(stroke
				(width 0.1)
				(type default)
			)
			(layer "F.Fab")
		)
		(fp_line
			(start 0.120396 0.2794)
			(end -0.12065 0.2794)
			(stroke
				(width 0.1)
				(type default)
			)
			(layer "F.Fab")
		)
		(fp_line
			(start -0.12065 -0.2794)
			(end 0.12065 -0.2794)
			(stroke
				(width 0.1)
				(type default)
			)
			(layer "F.Fab")
		)
		(fp_line
			(start 0.12065 -0.2794)
			(end 0.12065 -0.3048)
			(stroke
				(width 0.1)
				(type default)
			)
			(layer "F.Fab")
		)
		(fp_line
			(start 0.12065 -0.3048)
			(end 0.67945 -0.3048)
			(stroke
				(width 0.1)
				(type default)
			)
			(layer "F.Fab")
		)
		(fp_line
			(start 0.67945 -0.3048)
			(end 0.67945 0.3048)
			(stroke
				(width 0.1)
				(type default)
			)
			(layer "F.Fab")
		)
		(fp_line
			(start -0.67945 -0.305054)
			(end -0.12065 -0.305054)
			(stroke
				(width 0.1)
				(type default)
			)
			(layer "F.Fab")
		)
		(fp_line
			(start -0.12065 -0.305054)
			(end -0.12065 -0.2794)
			(stroke
				(width 0.1)
				(type default)
			)
			(layer "F.Fab")
		)
		(pad "1" smd circle
			(at -0.40005 0 270)
			(size 0 0)
			(layers "F.Cu" "F.Mask" "F.Paste")
			(net "MB0_P12V_STBY_PWRGD")
		)
		(pad "2" smd circle
			(at 0.40005 0 270)
			(size 0 0)
			(layers "F.Cu" "F.Mask" "F.Paste")
			(net "PWRGD_PS_PWROK")
		)
	)
	(footprint ""
		(layer "F.Cu")
		(at 148.98243 -75.350878)
		(property "Reference" "R2312"
			(at 0 0 0)
			(layer "F.SilkS")
			(hide yes)
			(effects
				(font
					(size 1.27 1.27)
				)
			)
		)
		(property "Value" ""
			(at 0 0 0)
			(layer "F.Fab")
			(effects
				(font
					(size 1.27 1.27)
				)
			)
		)
		(duplicate_pad_numbers_are_jumpers no)
		(fp_line
			(start -0.7874 -0.4064)
			(end 0.7874 -0.4064)
			(stroke
				(width 0.1524)
				(type default)
			)
			(layer "F.SilkS")
		)
		(fp_line
			(start -0.7874 0.4064)
			(end -0.7874 -0.4064)
			(stroke
				(width 0.1524)
				(type default)
			)
			(layer "F.SilkS")
		)
		(fp_line
			(start 0.7874 -0.4064)
			(end 0.7874 0.4064)
			(stroke
				(width 0.1524)
				(type default)
			)
			(layer "F.SilkS")
		)
		(fp_line
			(start 0.7874 0.4064)
			(end -0.7874 0.4064)
			(stroke
				(width 0.1524)
				(type default)
			)
			(layer "F.SilkS")
		)
		(fp_line
			(start -0.67945 -0.305054)
			(end -0.12065 -0.305054)
			(stroke
				(width 0.1)
				(type default)
			)
			(layer "F.Fab")
		)
		(fp_line
			(start -0.67945 0.3048)
			(end -0.67945 -0.305054)
			(stroke
				(width 0.1)
				(type default)
			)
			(layer "F.Fab")
		)
		(fp_line
			(start -0.12065 -0.305054)
			(end -0.12065 -0.2794)
			(stroke
				(width 0.1)
				(type default)
			)
			(layer "F.Fab")
		)
		(fp_line
			(start -0.12065 -0.2794)
			(end 0.12065 -0.2794)
			(stroke
				(width 0.1)
				(type default)
			)
			(layer "F.Fab")
		)
		(fp_line
			(start -0.12065 0.2794)
			(end -0.12065 0.3048)
			(stroke
				(width 0.1)
				(type default)
			)
			(layer "F.Fab")
		)
		(fp_line
			(start -0.12065 0.3048)
			(end -0.67945 0.3048)
			(stroke
				(width 0.1)
				(type default)
			)
			(layer "F.Fab")
		)
		(fp_line
			(start 0.120396 0.2794)
			(end -0.12065 0.2794)
			(stroke
				(width 0.1)
				(type default)
			)
			(layer "F.Fab")
		)
		(fp_line
			(start 0.120396 0.3048)
			(end 0.120396 0.2794)
			(stroke
				(width 0.1)
				(type default)
			)
			(layer "F.Fab")
		)
		(fp_line
			(start 0.12065 -0.3048)
			(end 0.67945 -0.3048)
			(stroke
				(width 0.1)
				(type default)
			)
			(layer "F.Fab")
		)
		(fp_line
			(start 0.12065 -0.2794)
			(end 0.12065 -0.3048)
			(stroke
				(width 0.1)
				(type default)
			)
			(layer "F.Fab")
		)
		(fp_line
			(start 0.67945 -0.3048)
			(end 0.67945 0.3048)
			(stroke
				(width 0.1)
				(type default)
			)
			(layer "F.Fab")
		)
		(fp_line
			(start 0.67945 0.3048)
			(end 0.120396 0.3048)
			(stroke
				(width 0.1)
				(type default)
			)
			(layer "F.Fab")
		)
		(pad "1" smd circle
			(at -0.40005 0)
			(size 0 0)
			(layers "F.Cu" "F.Mask" "F.Paste")
			(net "P3V3_AUX")
		)
		(pad "2" smd circle
			(at 0.40005 0)
			(size 0 0)
			(layers "F.Cu" "F.Mask" "F.Paste")
			(net "PCA9545_S3M_INT_N")
		)
	)
	(footprint ""
		(layer "F.Cu")
		(at 334.729074 -16.2052 -90)
		(property "Reference" "R1750"
			(at 0 0 270)
			(layer "F.SilkS")
			(hide yes)
			(effects
				(font
					(size 1.27 1.27)
				)
			)
		)
		(property "Value" ""
			(at 0 0 270)
			(layer "F.Fab")
			(effects
				(font
					(size 1.27 1.27)
				)
			)
		)
		(duplicate_pad_numbers_are_jumpers no)
		(fp_line
			(start -0.7874 0.4064)
			(end -0.7874 -0.4064)
			(stroke
				(width 0.1524)
				(type default)
			)
			(layer "F.SilkS")
		)
		(fp_line
			(start 0.7874 0.4064)
			(end -0.7874 0.4064)
			(stroke
				(width 0.1524)
				(type default)
			)
			(layer "F.SilkS")
		)
		(fp_line
			(start -0.7874 -0.4064)
			(end 0.7874 -0.4064)
			(stroke
				(width 0.1524)
				(type default)
			)
			(layer "F.SilkS")
		)
		(fp_line
			(start 0.7874 -0.4064)
			(end 0.7874 0.4064)
			(stroke
				(width 0.1524)
				(type default)
			)
			(layer "F.SilkS")
		)
		(fp_line
			(start -0.67945 0.3048)
			(end -0.67945 -0.305054)
			(stroke
				(width 0.1)
				(type default)
			)
			(layer "F.Fab")
		)
		(fp_line
			(start -0.12065 0.3048)
			(end -0.67945 0.3048)
			(stroke
				(width 0.1)
				(type default)
			)
			(layer "F.Fab")
		)
		(fp_line
			(start 0.120396 0.3048)
			(end 0.120396 0.2794)
			(stroke
				(width 0.1)
				(type default)
			)
			(layer "F.Fab")
		)
		(fp_line
			(start 0.67945 0.3048)
			(end 0.120396 0.3048)
			(stroke
				(width 0.1)
				(type default)
			)
			(layer "F.Fab")
		)
		(fp_line
			(start -0.12065 0.2794)
			(end -0.12065 0.3048)
			(stroke
				(width 0.1)
				(type default)
			)
			(layer "F.Fab")
		)
		(fp_line
			(start 0.120396 0.2794)
			(end -0.12065 0.2794)
			(stroke
				(width 0.1)
				(type default)
			)
			(layer "F.Fab")
		)
		(fp_line
			(start -0.12065 -0.2794)
			(end 0.12065 -0.2794)
			(stroke
				(width 0.1)
				(type default)
			)
			(layer "F.Fab")
		)
		(fp_line
			(start 0.12065 -0.2794)
			(end 0.12065 -0.3048)
			(stroke
				(width 0.1)
				(type default)
			)
			(layer "F.Fab")
		)
		(fp_line
			(start 0.12065 -0.3048)
			(end 0.67945 -0.3048)
			(stroke
				(width 0.1)
				(type default)
			)
			(layer "F.Fab")
		)
		(fp_line
			(start 0.67945 -0.3048)
			(end 0.67945 0.3048)
			(stroke
				(width 0.1)
				(type default)
			)
			(layer "F.Fab")
		)
		(fp_line
			(start -0.67945 -0.305054)
			(end -0.12065 -0.305054)
			(stroke
				(width 0.1)
				(type default)
			)
			(layer "F.Fab")
		)
		(fp_line
			(start -0.12065 -0.305054)
			(end -0.12065 -0.2794)
			(stroke
				(width 0.1)
				(type default)
			)
			(layer "F.Fab")
		)
		(pad "1" smd circle
			(at -0.40005 0 270)
			(size 0 0)
			(layers "F.Cu" "F.Mask" "F.Paste")
			(net "PGPPA_AUX")
		)
		(pad "2" smd circle
			(at 0.40005 0 270)
			(size 0 0)
			(layers "F.Cu" "F.Mask" "F.Paste")
			(net "FM_ESPI_PLD_R_EN_BUF")
		)
	)
	(footprint ""
		(layer "F.Cu")
		(at 392.719814 -36.318698 90)
		(property "Reference" "U210"
			(at 0.01016 2.864866 0)
			(unlocked yes)
			(layer "F.SilkS")
			(effects
				(font
					(size 0.7874 0.5842)
					(thickness 0.1524)
				)
				(justify left)
			)
		)
		(property "Value" ""
			(at 0 0 90)
			(layer "F.Fab")
			(effects
				(font
					(size 1.27 1.27)
				)
			)
		)
		(duplicate_pad_numbers_are_jumpers no)
		(fp_line
			(start 1.733296 -1.549908)
			(end 0.660908 -1.549908)
			(stroke
				(width 0.1524)
				(type default)
			)
			(layer "F.SilkS")
		)
		(fp_line
			(start 0.660908 -1.549908)
			(end 0 -0.889)
			(stroke
				(width 0.1524)
				(type default)
			)
			(layer "F.SilkS")
		)
		(fp_line
			(start -0.660908 -1.549908)
			(end -1.733296 -1.549908)
			(stroke
				(width 0.1524)
				(type default)
			)
			(layer "F.SilkS")
		)
		(fp_line
			(start -1.733296 -1.549908)
			(end -1.733296 1.549908)
			(stroke
				(width 0.1524)
				(type default)
			)
			(layer "F.SilkS")
		)
		(fp_line
			(start 0 -0.889)
			(end -0.660908 -1.549908)
			(stroke
				(width 0.1524)
				(type default)
			)
			(layer "F.SilkS")
		)
		(fp_line
			(start 1.733296 1.549908)
			(end 1.733296 -1.549908)
			(stroke
				(width 0.1524)
				(type default)
			)
			(layer "F.SilkS")
		)
		(fp_line
			(start -1.733296 1.549908)
			(end 1.733296 1.549908)
			(stroke
				(width 0.1524)
				(type default)
			)
			(layer "F.SilkS")
		)
		(fp_poly
			(pts
				(xy -1.9304 -0.94996) (xy -2.4384 -0.69596) (xy -2.4384 -1.20396)
			)
			(stroke
				(width 0)
				(type default)
			)
			(fill yes)
			(layer "F.SilkS")
		)
		(fp_line
			(start 0.849884 -1.549908)
			(end -0.849884 -1.549908)
			(stroke
				(width 0.1)
				(type default)
			)
			(layer "F.Fab")
		)
		(fp_line
			(start -0.849884 -1.549908)
			(end -0.849884 1.549908)
			(stroke
				(width 0.1)
				(type default)
			)
			(layer "F.Fab")
		)
		(fp_line
			(start 0.849884 1.549908)
			(end 0.849884 -1.549908)
			(stroke
				(width 0.1)
				(type default)
			)
			(layer "F.Fab")
		)
		(fp_line
			(start -0.849884 1.549908)
			(end 0.849884 1.549908)
			(stroke
				(width 0.1)
				(type default)
			)
			(layer "F.Fab")
		)
		(fp_poly
			(pts
				(xy -2.4384 -1.20396) (xy -2.4384 -0.69596) (xy -1.9304 -0.94996)
			)
			(stroke
				(width 0)
				(type default)
			)
			(fill yes)
			(layer "F.Fab")
		)
		(pad "1" smd rect
			(at -1.199896 -0.94996)
			(size 0.5588 0.8128)
			(layers "F.Cu" "F.Mask" "F.Paste")
			(net "HP_LVC3_OCP_V3_1_PWRGD_R")
		)
		(pad "2" smd rect
			(at -1.199896 0)
			(size 0.5588 0.8128)
			(layers "F.Cu" "F.Mask" "F.Paste")
			(net "RST_OCP_V3_1_N")
		)
		(pad "3" smd rect
			(at -1.199896 0.94996)
			(size 0.5588 0.8128)
			(layers "F.Cu" "F.Mask" "F.Paste")
			(net "GND")
		)
		(pad "4" smd rect
			(at 1.199896 0.94996)
			(size 0.5588 0.8128)
			(layers "F.Cu" "F.Mask" "F.Paste")
			(net "RST_HP_OCP_V3_1_N")
		)
		(pad "5" smd rect
			(at 1.199896 -0.94996)
			(size 0.5588 0.8128)
			(layers "F.Cu" "F.Mask" "F.Paste")
			(net "P3V3_AUX")
		)
	)
	(footprint ""
		(layer "F.Cu")
		(at 68.594478 -408.517344 -90)
		(property "Reference" "C697"
			(at 0 0 270)
			(layer "F.SilkS")
			(hide yes)
			(effects
				(font
					(size 1.27 1.27)
				)
			)
		)
		(property "Value" ""
			(at 0 0 270)
			(layer "F.Fab")
			(effects
				(font
					(size 1.27 1.27)
				)
			)
		)
		(duplicate_pad_numbers_are_jumpers no)
		(fp_line
			(start -0.299974 0.150114)
			(end -0.299974 -0.150114)
			(stroke
				(width 0.1)
				(type default)
			)
			(layer "F.Fab")
		)
		(fp_line
			(start 0.299974 0.150114)
			(end -0.299974 0.150114)
			(stroke
				(width 0.1)
				(type default)
			)
			(layer "F.Fab")
		)
		(fp_line
			(start -0.299974 -0.150114)
			(end 0.299974 -0.150114)
			(stroke
				(width 0.1)
				(type default)
			)
			(layer "F.Fab")
		)
		(fp_line
			(start 0.299974 -0.150114)
			(end 0.299974 0.150114)
			(stroke
				(width 0.1)
				(type default)
			)
			(layer "F.Fab")
		)
		(pad "1" smd rect
			(at -0.2667 0 270)
			(size 0.3048 0.381)
			(layers "F.Cu" "F.Mask" "F.Paste")
			(net "P5E_CPU1_PE4_TX_C_DP<6>")
		)
		(pad "2" smd rect
			(at 0.2667 0 270)
			(size 0.3048 0.381)
			(layers "F.Cu" "F.Mask" "F.Paste")
			(net "P5E_CPU1_PE4_TX_DP<6>")
		)
	)
	(footprint ""
		(layer "F.Cu")
		(at 310.995568 -402.371052 -90)
		(property "Reference" "C1575"
			(at 0 0 270)
			(layer "F.SilkS")
			(hide yes)
			(effects
				(font
					(size 1.27 1.27)
				)
			)
		)
		(property "Value" ""
			(at 0 0 270)
			(layer "F.Fab")
			(effects
				(font
					(size 1.27 1.27)
				)
			)
		)
		(duplicate_pad_numbers_are_jumpers no)
		(fp_line
			(start -0.299974 0.150114)
			(end -0.299974 -0.150114)
			(stroke
				(width 0.1)
				(type default)
			)
			(layer "F.Fab")
		)
		(fp_line
			(start 0.299974 0.150114)
			(end -0.299974 0.150114)
			(stroke
				(width 0.1)
				(type default)
			)
			(layer "F.Fab")
		)
		(fp_line
			(start -0.299974 -0.150114)
			(end 0.299974 -0.150114)
			(stroke
				(width 0.1)
				(type default)
			)
			(layer "F.Fab")
		)
		(fp_line
			(start 0.299974 -0.150114)
			(end 0.299974 0.150114)
			(stroke
				(width 0.1)
				(type default)
			)
			(layer "F.Fab")
		)
		(pad "1" smd rect
			(at -0.2667 0 270)
			(size 0.3048 0.381)
			(layers "F.Cu" "F.Mask" "F.Paste")
			(net "P5E_CPU0_PE4_TX_C_DP<2>")
		)
		(pad "2" smd rect
			(at 0.2667 0 270)
			(size 0.3048 0.381)
			(layers "F.Cu" "F.Mask" "F.Paste")
			(net "P5E_CPU0_PE4_TX_DP<2>")
		)
	)
)
